FILE_TYPE = MACRO_DRAWING;
SET COLOR_WIRE YELLOW;
SET COLOR_PROP ORANGE;
SET COLOR_DOT WHITE;
SET COLOR_ARC YELLOW;
SET COLOR_BODY GREEN;
SET COLOR_NOTE PURPLE;
SET PROP_DISPLAY VALUE;
SET PAGE_NUMBER P356;
FORCEADD QUANTA_TITLE_BLOCK_C..1
(0 0);
FORCEPROP 1 LAST CUSTOM_TXT_CDS <NAME_2>
J 0
(-3175 50);
FORCEPROP 1 LAST CUSTOM_TXT_CDS <NAME_1>
J 0
(-3175 175);
FORCEPROP 1 LAST CUSTOM_TXT_CDS <Q_NUMBER>
J 0
(-1403 103);
DISPLAY 1.212766 (-1403 103);
FORCEPROP 1 LAST CUSTOM_TXT_CDS <Q_PROJ>
J 0
(-2382 102);
DISPLAY 1.212766 (-2382 102);
FORCEPROP 1 LAST CUSTOM_TXT_CDS <Q_REV>
J 0
(-184 103);
DISPLAY 1.212766 (-184 103);
FORCEPROP 1 LAST CUSTOM_TXT_CDS <CON_LAST_MODIFIED>
J 0
(-1885 15);
DISPLAY 0.978723 (-1885 15);
FORCEPROP 1 LAST CUSTOM_TXT_CDS <CON_PAGE_NUM> OF <CON_TOTAL_PAGES>
J 0
(-446 18);
DISPLAY 0.978723 (-446 18);
FORCEPROP 1 LAST Q_TITLE Blank
J 0
(-9366 26);
DISPLAY 2.446809 (-9366 26);
PAINT GREEN (-9366 26);
FORCEPROP 2 LAST CDS_LIB pure_quanta
J 0
(0 0);
DISPLAY INVISIBLE (0 0);
FORCEPROP 1 LAST CDS_LMAN_SYM_OUTLINE -9475,6775,100,-125
J 0
(0 0);
DISPLAY 0.468085 (0 0);
PAINT GREEN (0 0);
DISPLAY INVISIBLE (0 0);
FORCEPROP 2 LAST PAGE_BORDER TRUE
J 0
(-7890 5250);
DISPLAY 0.638298 (-7890 5250);
PAINT PINK (-7890 5250);
DISPLAY INVISIBLE (-7890 5250);
FORCEPROP 2 LAST CDS_XR_PAGE_TITLE CR-233 : @T6G_MB_LIB.T6G(SCH_1):PAGE233
J 0
(-7890 5250);
DISPLAY 0.638298 (-7890 5250);
PAINT PINK (-7890 5250);
DISPLAY INVISIBLE (-7890 5250);
FORCEPROP 2 LAST CUSTOM_TXT_CDS <XR_PAGE_TITLE>
J 0
(-7890 5250);
DISPLAY 0.638298 (-7890 5250);
PAINT PINK (-7890 5250);
DISPLAY INVISIBLE (-7890 5250);
FORCEPROP 1 LAST COMMENT_BODY TRUE
J 0
(12 -13);
DISPLAY 0.978723 (12 -13);
PAINT GREEN (12 -13);
DISPLAY INVISIBLE (12 -13);
FORCEPROP 1 LAST Q_DEPT BU9
J 1
(-3763 49);
DISPLAY 1.957447 (-3763 49);
PAINT GREEN (-3763 49);
DISPLAY INVISIBLE (-3763 49);
FORCEPROP 0 LAST CDS_CON_LAST_MODIFIED Thu Aug 24 10:15:32 2023
J 0
(-1885 15);
DISPLAY INVISIBLE (-1885 15);
QUIT
